(kicad_pcb
	(version 20260206)
	(generator "pcbnew")
	(generator_version "10.0")
	(general
		(thickness 1.6)
		(legacy_teardrops no)
	)
	(paper "A4")
	(title_block
		(title "04192023_DAF0TMB3IC0_F0TG_MB_C_brd_V02_OCP.brd")
		(comment 1 "Grand Teton / footprints 2675-2680 of 8354")
	)
	(layers
		(0 "F.Cu" signal "TOP")
		(4 "In1.Cu" signal "GND")
		(6 "In2.Cu" signal "IN1")
		(8 "In3.Cu" signal "GND1")
		(10 "In4.Cu" signal "IN2")
		(12 "In5.Cu" signal "GND2")
		(14 "In6.Cu" signal "IN3")
		(16 "In7.Cu" signal "GND3")
		(18 "In8.Cu" signal "VCC")
		(20 "In9.Cu" signal "VCC1")
		(22 "In10.Cu" signal "GND4")
		(24 "In11.Cu" signal "IN4")
		(26 "In12.Cu" signal "GND5")
		(28 "In13.Cu" signal "IN5")
		(30 "In14.Cu" signal "GND6")
		(32 "In15.Cu" signal "IN6")
		(34 "In16.Cu" signal "GND7")
		(2 "B.Cu" signal "BOTTOM")
		(9 "F.Adhes" user "F.Adhesive")
		(11 "B.Adhes" user "B.Adhesive")
		(13 "F.Paste" user "Package Geometry/Pastemask Top")
		(15 "B.Paste" user "Package Geometry/Pastemask Bottom")
		(5 "F.SilkS" user "Ref Des/Silkscreen Top")
		(7 "B.SilkS" user "Ref Des/Silkscreen Bottom")
		(1 "F.Mask" user "Board Geometry/Soldermask Top")
		(3 "B.Mask" user "Board Geometry/Soldermask Bottom")
		(17 "Dwgs.User" user "User.Drawings")
		(19 "Cmts.User" user "User.Comments")
		(21 "Eco1.User" user "User.Eco1")
		(23 "Eco2.User" user "User.Eco2")
		(25 "Edge.Cuts" user "Board Geometry/Outline")
		(27 "Margin" user)
		(31 "F.CrtYd" user "Package Geometry/Place Bound Top")
		(29 "B.CrtYd" user "Package Geometry/Place Bound Bottom")
		(35 "F.Fab" user "Ref Des/Assembly Top")
		(33 "B.Fab" user "Ref Des/Assembly Bottom")
	)
	(footprint ""
		(layer "F.Cu")
		(at 416.179 -99.441 -90)
		(property "Reference" "U8001"
			(at -3.030474 1.59004 0)
			(unlocked yes)
			(layer "F.SilkS")
			(effects
				(font
					(size 0.7874 0.5842)
					(thickness 0.1524)
				)
				(justify left)
			)
		)
		(property "Value" ""
			(at 0 0 270)
			(layer "F.Fab")
			(effects
				(font
					(size 1.27 1.27)
				)
			)
		)
		(duplicate_pad_numbers_are_jumpers no)
		(fp_line
			(start -1.759712 1.500124)
			(end -1.759712 -1.500124)
			(stroke
				(width 0.1524)
				(type default)
			)
			(layer "F.SilkS")
		)
		(fp_line
			(start 1.759712 1.500124)
			(end -1.759712 1.500124)
			(stroke
				(width 0.1524)
				(type default)
			)
			(layer "F.SilkS")
		)
		(fp_line
			(start -1.759712 -1.500124)
			(end 1.759712 -1.500124)
			(stroke
				(width 0.1524)
				(type default)
			)
			(layer "F.SilkS")
		)
		(fp_line
			(start 1.759712 -1.500124)
			(end 1.759712 1.500124)
			(stroke
				(width 0.1524)
				(type default)
			)
			(layer "F.SilkS")
		)
		(fp_line
			(start -0.700024 1.500124)
			(end -0.700024 -1.500124)
			(stroke
				(width 0.1)
				(type default)
			)
			(layer "F.Fab")
		)
		(fp_line
			(start 0.700024 1.500124)
			(end -0.700024 1.500124)
			(stroke
				(width 0.1)
				(type default)
			)
			(layer "F.Fab")
		)
		(fp_line
			(start -0.700024 -1.500124)
			(end 0.700024 -1.500124)
			(stroke
				(width 0.1)
				(type default)
			)
			(layer "F.Fab")
		)
		(fp_line
			(start 0.700024 -1.500124)
			(end 0.700024 1.500124)
			(stroke
				(width 0.1)
				(type default)
			)
			(layer "F.Fab")
		)
		(pad "1" smd rect
			(at -1.150112 -0.94996 180)
			(size 0.6604 0.9652)
			(layers "F.Cu" "F.Mask" "F.Paste")
			(net "GND")
		)
		(pad "2" smd rect
			(at -1.150112 0.94996 180)
			(size 0.6604 0.9652)
			(layers "F.Cu" "F.Mask" "F.Paste")
			(net "OCP_V3_1_P3V3_R1_PWRGD")
		)
		(pad "3" smd rect
			(at 1.150112 0 180)
			(size 0.6604 0.9652)
			(layers "F.Cu" "F.Mask" "F.Paste")
			(net "P3V3_OCP_SFF_R")
		)
	)
	(footprint ""
		(layer "F.Cu")
		(at 449.443602 -422.01211 180)
		(property "Reference" "PR6603"
			(at 0 0 180)
			(layer "F.SilkS")
			(hide yes)
			(effects
				(font
					(size 1.27 1.27)
				)
			)
		)
		(property "Value" ""
			(at 0 0 180)
			(layer "F.Fab")
			(effects
				(font
					(size 1.27 1.27)
				)
			)
		)
		(duplicate_pad_numbers_are_jumpers no)
		(fp_line
			(start 0.7874 0.4064)
			(end -0.7874 0.4064)
			(stroke
				(width 0.1524)
				(type default)
			)
			(layer "F.SilkS")
		)
		(fp_line
			(start 0.7874 -0.4064)
			(end 0.7874 0.4064)
			(stroke
				(width 0.1524)
				(type default)
			)
			(layer "F.SilkS")
		)
		(fp_line
			(start -0.7874 0.4064)
			(end -0.7874 -0.4064)
			(stroke
				(width 0.1524)
				(type default)
			)
			(layer "F.SilkS")
		)
		(fp_line
			(start -0.7874 -0.4064)
			(end 0.7874 -0.4064)
			(stroke
				(width 0.1524)
				(type default)
			)
			(layer "F.SilkS")
		)
		(fp_line
			(start 0.67945 0.3048)
			(end 0.120396 0.3048)
			(stroke
				(width 0.1)
				(type default)
			)
			(layer "F.Fab")
		)
		(fp_line
			(start 0.67945 -0.3048)
			(end 0.67945 0.3048)
			(stroke
				(width 0.1)
				(type default)
			)
			(layer "F.Fab")
		)
		(fp_line
			(start 0.12065 -0.2794)
			(end 0.12065 -0.3048)
			(stroke
				(width 0.1)
				(type default)
			)
			(layer "F.Fab")
		)
		(fp_line
			(start 0.12065 -0.3048)
			(end 0.67945 -0.3048)
			(stroke
				(width 0.1)
				(type default)
			)
			(layer "F.Fab")
		)
		(fp_line
			(start 0.120396 0.3048)
			(end 0.120396 0.2794)
			(stroke
				(width 0.1)
				(type default)
			)
			(layer "F.Fab")
		)
		(fp_line
			(start 0.120396 0.2794)
			(end -0.12065 0.2794)
			(stroke
				(width 0.1)
				(type default)
			)
			(layer "F.Fab")
		)
		(fp_line
			(start -0.12065 0.3048)
			(end -0.67945 0.3048)
			(stroke
				(width 0.1)
				(type default)
			)
			(layer "F.Fab")
		)
		(fp_line
			(start -0.12065 0.2794)
			(end -0.12065 0.3048)
			(stroke
				(width 0.1)
				(type default)
			)
			(layer "F.Fab")
		)
		(fp_line
			(start -0.12065 -0.2794)
			(end 0.12065 -0.2794)
			(stroke
				(width 0.1)
				(type default)
			)
			(layer "F.Fab")
		)
		(fp_line
			(start -0.12065 -0.305054)
			(end -0.12065 -0.2794)
			(stroke
				(width 0.1)
				(type default)
			)
			(layer "F.Fab")
		)
		(fp_line
			(start -0.67945 0.3048)
			(end -0.67945 -0.305054)
			(stroke
				(width 0.1)
				(type default)
			)
			(layer "F.Fab")
		)
		(fp_line
			(start -0.67945 -0.305054)
			(end -0.12065 -0.305054)
			(stroke
				(width 0.1)
				(type default)
			)
			(layer "F.Fab")
		)
		(pad "1" smd circle
			(at -0.40005 0 180)
			(size 0 0)
			(layers "F.Cu" "F.Mask" "F.Paste")
			(net "GND")
		)
		(pad "2" smd circle
			(at 0.40005 0 180)
			(size 0 0)
			(layers "F.Cu" "F.Mask" "F.Paste")
			(net "P0V9_RETIMER_CPU0_ADDR")
		)
	)
	(footprint ""
		(layer "F.Cu")
		(at 423.35704 -435.436772)
		(property "Reference" "Q135"
			(at -1.4224 -1.768348 0)
			(unlocked yes)
			(layer "F.SilkS")
			(effects
				(font
					(size 0.7874 0.5842)
					(thickness 0.1524)
				)
				(justify left)
			)
		)
		(property "Value" ""
			(at 0 0 0)
			(layer "F.Fab")
			(effects
				(font
					(size 1.27 1.27)
				)
			)
		)
		(duplicate_pad_numbers_are_jumpers no)
		(fp_line
			(start -1.332738 -1.100074)
			(end -0.4826 -1.100074)
			(stroke
				(width 0.1524)
				(type default)
			)
			(layer "F.SilkS")
		)
		(fp_line
			(start -1.332738 1.100074)
			(end -1.332738 -1.100074)
			(stroke
				(width 0.1524)
				(type default)
			)
			(layer "F.SilkS")
		)
		(fp_line
			(start -0.4826 -1.100074)
			(end 0 -0.541274)
			(stroke
				(width 0.1524)
				(type default)
			)
			(layer "F.SilkS")
		)
		(fp_line
			(start 0 -0.541274)
			(end 0.4826 -1.100074)
			(stroke
				(width 0.1524)
				(type default)
			)
			(layer "F.SilkS")
		)
		(fp_line
			(start 0.4826 -1.100074)
			(end 1.332738 -1.100074)
			(stroke
				(width 0.1524)
				(type default)
			)
			(layer "F.SilkS")
		)
		(fp_line
			(start 1.332738 -1.100074)
			(end 1.332738 1.100074)
			(stroke
				(width 0.1524)
				(type default)
			)
			(layer "F.SilkS")
		)
		(fp_line
			(start 1.332738 1.100074)
			(end -1.332738 1.100074)
			(stroke
				(width 0.1524)
				(type default)
			)
			(layer "F.SilkS")
		)
		(fp_poly
			(pts
				(xy -1.467104 -1.206246) (xy -2.16916 -0.855218) (xy -2.16916 -1.557274)
			)
			(stroke
				(width 0)
				(type default)
			)
			(fill yes)
			(layer "F.SilkS")
		)
		(fp_line
			(start -0.674878 -1.100074)
			(end 0.674878 -1.100074)
			(stroke
				(width 0.1)
				(type default)
			)
			(layer "F.Fab")
		)
		(fp_line
			(start -0.674878 1.100074)
			(end -0.674878 -1.100074)
			(stroke
				(width 0.1)
				(type default)
			)
			(layer "F.Fab")
		)
		(fp_line
			(start 0.674878 -1.100074)
			(end 0.674878 1.100074)
			(stroke
				(width 0.1)
				(type default)
			)
			(layer "F.Fab")
		)
		(fp_line
			(start 0.674878 1.100074)
			(end -0.674878 1.100074)
			(stroke
				(width 0.1)
				(type default)
			)
			(layer "F.Fab")
		)
		(fp_poly
			(pts
				(xy -2.2352 -0.298958) (xy -2.2352 -1.001014) (xy -1.533144 -0.649986)
			)
			(stroke
				(width 0)
				(type default)
			)
			(fill yes)
			(layer "F.Fab")
		)
		(pad "1" smd rect
			(at -0.94996 -0.649986 90)
			(size 0.4318 0.508)
			(layers "F.Cu" "F.Mask" "F.Paste")
			(net "GND")
		)
		(pad "2" smd rect
			(at -0.94996 0 90)
			(size 0.4318 0.508)
			(layers "F.Cu" "F.Mask" "F.Paste")
			(net "GPU_3V3IO_RSVD1")
		)
		(pad "3" smd rect
			(at -0.94996 0.649986 90)
			(size 0.4318 0.508)
			(layers "F.Cu" "F.Mask" "F.Paste")
			(net "GPU_3V3IO_RSVD1_ISO")
		)
		(pad "4" smd rect
			(at 0.94996 0.649986 90)
			(size 0.4318 0.508)
			(layers "F.Cu" "F.Mask" "F.Paste")
			(net "GND")
		)
		(pad "5" smd rect
			(at 0.94996 0 90)
			(size 0.4318 0.508)
			(layers "F.Cu" "F.Mask" "F.Paste")
			(net "GPU_3V3IO_RSVD1_N")
		)
		(pad "6" smd rect
			(at 0.94996 -0.649986 90)
			(size 0.4318 0.508)
			(layers "F.Cu" "F.Mask" "F.Paste")
			(net "GPU_3V3IO_RSVD1_N")
		)
	)
	(footprint ""
		(layer "F.Cu")
		(at 291.799772 -18.983452)
		(property "Reference" "R4182"
			(at 0 0 0)
			(layer "F.SilkS")
			(hide yes)
			(effects
				(font
					(size 1.27 1.27)
				)
			)
		)
		(property "Value" ""
			(at 0 0 0)
			(layer "F.Fab")
			(effects
				(font
					(size 1.27 1.27)
				)
			)
		)
		(duplicate_pad_numbers_are_jumpers no)
		(fp_line
			(start -0.7874 -0.4064)
			(end 0.7874 -0.4064)
			(stroke
				(width 0.1524)
				(type default)
			)
			(layer "F.SilkS")
		)
		(fp_line
			(start -0.7874 0.4064)
			(end -0.7874 -0.4064)
			(stroke
				(width 0.1524)
				(type default)
			)
			(layer "F.SilkS")
		)
		(fp_line
			(start 0.7874 -0.4064)
			(end 0.7874 0.4064)
			(stroke
				(width 0.1524)
				(type default)
			)
			(layer "F.SilkS")
		)
		(fp_line
			(start 0.7874 0.4064)
			(end -0.7874 0.4064)
			(stroke
				(width 0.1524)
				(type default)
			)
			(layer "F.SilkS")
		)
		(fp_line
			(start -0.67945 -0.305054)
			(end -0.12065 -0.305054)
			(stroke
				(width 0.1)
				(type default)
			)
			(layer "F.Fab")
		)
		(fp_line
			(start -0.67945 0.3048)
			(end -0.67945 -0.305054)
			(stroke
				(width 0.1)
				(type default)
			)
			(layer "F.Fab")
		)
		(fp_line
			(start -0.12065 -0.305054)
			(end -0.12065 -0.2794)
			(stroke
				(width 0.1)
				(type default)
			)
			(layer "F.Fab")
		)
		(fp_line
			(start -0.12065 -0.2794)
			(end 0.12065 -0.2794)
			(stroke
				(width 0.1)
				(type default)
			)
			(layer "F.Fab")
		)
		(fp_line
			(start -0.12065 0.2794)
			(end -0.12065 0.3048)
			(stroke
				(width 0.1)
				(type default)
			)
			(layer "F.Fab")
		)
		(fp_line
			(start -0.12065 0.3048)
			(end -0.67945 0.3048)
			(stroke
				(width 0.1)
				(type default)
			)
			(layer "F.Fab")
		)
		(fp_line
			(start 0.120396 0.2794)
			(end -0.12065 0.2794)
			(stroke
				(width 0.1)
				(type default)
			)
			(layer "F.Fab")
		)
		(fp_line
			(start 0.120396 0.3048)
			(end 0.120396 0.2794)
			(stroke
				(width 0.1)
				(type default)
			)
			(layer "F.Fab")
		)
		(fp_line
			(start 0.12065 -0.3048)
			(end 0.67945 -0.3048)
			(stroke
				(width 0.1)
				(type default)
			)
			(layer "F.Fab")
		)
		(fp_line
			(start 0.12065 -0.2794)
			(end 0.12065 -0.3048)
			(stroke
				(width 0.1)
				(type default)
			)
			(layer "F.Fab")
		)
		(fp_line
			(start 0.67945 -0.3048)
			(end 0.67945 0.3048)
			(stroke
				(width 0.1)
				(type default)
			)
			(layer "F.Fab")
		)
		(fp_line
			(start 0.67945 0.3048)
			(end 0.120396 0.3048)
			(stroke
				(width 0.1)
				(type default)
			)
			(layer "F.Fab")
		)
		(pad "1" smd circle
			(at -0.40005 0)
			(size 0 0)
			(layers "F.Cu" "F.Mask" "F.Paste")
			(net "SMB_LM75_1_3V3AUX_SDA")
		)
		(pad "2" smd circle
			(at 0.40005 0)
			(size 0 0)
			(layers "F.Cu" "F.Mask" "F.Paste")
			(net "SMB_LM75_1_3V3AUX_SDA_R1")
		)
	)
	(footprint ""
		(layer "F.Cu")
		(at 370.225066 -424.002962 90)
		(property "Reference" "R4191"
			(at 0 0 90)
			(layer "F.SilkS")
			(hide yes)
			(effects
				(font
					(size 1.27 1.27)
				)
			)
		)
		(property "Value" ""
			(at 0 0 90)
			(layer "F.Fab")
			(effects
				(font
					(size 1.27 1.27)
				)
			)
		)
		(duplicate_pad_numbers_are_jumpers no)
		(fp_line
			(start 0.7874 -0.4064)
			(end 0.7874 0.4064)
			(stroke
				(width 0.1524)
				(type default)
			)
			(layer "F.SilkS")
		)
		(fp_line
			(start -0.7874 -0.4064)
			(end 0.7874 -0.4064)
			(stroke
				(width 0.1524)
				(type default)
			)
			(layer "F.SilkS")
		)
		(fp_line
			(start 0.7874 0.4064)
			(end -0.7874 0.4064)
			(stroke
				(width 0.1524)
				(type default)
			)
			(layer "F.SilkS")
		)
		(fp_line
			(start -0.7874 0.4064)
			(end -0.7874 -0.4064)
			(stroke
				(width 0.1524)
				(type default)
			)
			(layer "F.SilkS")
		)
		(fp_line
			(start -0.12065 -0.305054)
			(end -0.12065 -0.2794)
			(stroke
				(width 0.1)
				(type default)
			)
			(layer "F.Fab")
		)
		(fp_line
			(start -0.67945 -0.305054)
			(end -0.12065 -0.305054)
			(stroke
				(width 0.1)
				(type default)
			)
			(layer "F.Fab")
		)
		(fp_line
			(start 0.67945 -0.3048)
			(end 0.67945 0.3048)
			(stroke
				(width 0.1)
				(type default)
			)
			(layer "F.Fab")
		)
		(fp_line
			(start 0.12065 -0.3048)
			(end 0.67945 -0.3048)
			(stroke
				(width 0.1)
				(type default)
			)
			(layer "F.Fab")
		)
		(fp_line
			(start 0.12065 -0.2794)
			(end 0.12065 -0.3048)
			(stroke
				(width 0.1)
				(type default)
			)
			(layer "F.Fab")
		)
		(fp_line
			(start -0.12065 -0.2794)
			(end 0.12065 -0.2794)
			(stroke
				(width 0.1)
				(type default)
			)
			(layer "F.Fab")
		)
		(fp_line
			(start 0.120396 0.2794)
			(end -0.12065 0.2794)
			(stroke
				(width 0.1)
				(type default)
			)
			(layer "F.Fab")
		)
		(fp_line
			(start -0.12065 0.2794)
			(end -0.12065 0.3048)
			(stroke
				(width 0.1)
				(type default)
			)
			(layer "F.Fab")
		)
		(fp_line
			(start 0.67945 0.3048)
			(end 0.120396 0.3048)
			(stroke
				(width 0.1)
				(type default)
			)
			(layer "F.Fab")
		)
		(fp_line
			(start 0.120396 0.3048)
			(end 0.120396 0.2794)
			(stroke
				(width 0.1)
				(type default)
			)
			(layer "F.Fab")
		)
		(fp_line
			(start -0.12065 0.3048)
			(end -0.67945 0.3048)
			(stroke
				(width 0.1)
				(type default)
			)
			(layer "F.Fab")
		)
		(fp_line
			(start -0.67945 0.3048)
			(end -0.67945 -0.305054)
			(stroke
				(width 0.1)
				(type default)
			)
			(layer "F.Fab")
		)
		(pad "1" smd circle
			(at -0.40005 0 90)
			(size 0 0)
			(layers "F.Cu" "F.Mask" "F.Paste")
			(net "U270_0_ADD2")
		)
		(pad "2" smd circle
			(at 0.40005 0 90)
			(size 0 0)
			(layers "F.Cu" "F.Mask" "F.Paste")
			(net "GND")
		)
	)
	(footprint ""
		(layer "F.Cu")
		(at 54.30266 -351.372932 90)
		(property "Reference" "PR279"
			(at 0 0 90)
			(layer "F.SilkS")
			(hide yes)
			(effects
				(font
					(size 1.27 1.27)
				)
			)
		)
		(property "Value" ""
			(at 0 0 90)
			(layer "F.Fab")
			(effects
				(font
					(size 1.27 1.27)
				)
			)
		)
		(duplicate_pad_numbers_are_jumpers no)
		(fp_line
			(start 0.7874 -0.4064)
			(end 0.7874 0.4064)
			(stroke
				(width 0.1524)
				(type default)
			)
			(layer "F.SilkS")
		)
		(fp_line
			(start -0.7874 -0.4064)
			(end 0.7874 -0.4064)
			(stroke
				(width 0.1524)
				(type default)
			)
			(layer "F.SilkS")
		)
		(fp_line
			(start 0.7874 0.4064)
			(end -0.7874 0.4064)
			(stroke
				(width 0.1524)
				(type default)
			)
			(layer "F.SilkS")
		)
		(fp_line
			(start -0.7874 0.4064)
			(end -0.7874 -0.4064)
			(stroke
				(width 0.1524)
				(type default)
			)
			(layer "F.SilkS")
		)
		(fp_line
			(start -0.12065 -0.305054)
			(end -0.12065 -0.2794)
			(stroke
				(width 0.1)
				(type default)
			)
			(layer "F.Fab")
		)
		(fp_line
			(start -0.67945 -0.305054)
			(end -0.12065 -0.305054)
			(stroke
				(width 0.1)
				(type default)
			)
			(layer "F.Fab")
		)
		(fp_line
			(start 0.67945 -0.3048)
			(end 0.67945 0.3048)
			(stroke
				(width 0.1)
				(type default)
			)
			(layer "F.Fab")
		)
		(fp_line
			(start 0.12065 -0.3048)
			(end 0.67945 -0.3048)
			(stroke
				(width 0.1)
				(type default)
			)
			(layer "F.Fab")
		)
		(fp_line
			(start 0.12065 -0.2794)
			(end 0.12065 -0.3048)
			(stroke
				(width 0.1)
				(type default)
			)
			(layer "F.Fab")
		)
		(fp_line
			(start -0.12065 -0.2794)
			(end 0.12065 -0.2794)
			(stroke
				(width 0.1)
				(type default)
			)
			(layer "F.Fab")
		)
		(fp_line
			(start 0.120396 0.2794)
			(end -0.12065 0.2794)
			(stroke
				(width 0.1)
				(type default)
			)
			(layer "F.Fab")
		)
		(fp_line
			(start -0.12065 0.2794)
			(end -0.12065 0.3048)
			(stroke
				(width 0.1)
				(type default)
			)
			(layer "F.Fab")
		)
		(fp_line
			(start 0.67945 0.3048)
			(end 0.120396 0.3048)
			(stroke
				(width 0.1)
				(type default)
			)
			(layer "F.Fab")
		)
		(fp_line
			(start 0.120396 0.3048)
			(end 0.120396 0.2794)
			(stroke
				(width 0.1)
				(type default)
			)
			(layer "F.Fab")
		)
		(fp_line
			(start -0.12065 0.3048)
			(end -0.67945 0.3048)
			(stroke
				(width 0.1)
				(type default)
			)
			(layer "F.Fab")
		)
		(fp_line
			(start -0.67945 0.3048)
			(end -0.67945 -0.305054)
			(stroke
				(width 0.1)
				(type default)
			)
			(layer "F.Fab")
		)
		(pad "1" smd circle
			(at -0.40005 0 90)
			(size 0 0)
			(layers "F.Cu" "F.Mask" "F.Paste")
			(net "SW_PVDDIO_P1_BOOT1")
		)
		(pad "2" smd circle
			(at 0.40005 0 90)
			(size 0 0)
			(layers "F.Cu" "F.Mask" "F.Paste")
			(net "SW_PVDDIO_P1_BOOT1_R")
		)
	)
)
